(kicad_pcb
	(version 20260206)
	(generator "pcbnew")
	(generator_version "10.0")
	(general
		(thickness 1.6)
		(legacy_teardrops no)
	)
	(paper "A4")
	(title_block
		(title "Wiwynn_Tioga_Pass_MB.brd")
		(comment 1 "Tioga Pass / footprints 727-734 of 4770")
	)
	(layers
		(0 "F.Cu" signal "TOP")
		(4 "In1.Cu" signal "L2GND")
		(6 "In2.Cu" signal "L3")
		(8 "In3.Cu" signal "L4GND")
		(10 "In4.Cu" signal "L5")
		(12 "In5.Cu" signal "L6GND")
		(14 "In6.Cu" signal "L7VCC")
		(16 "In7.Cu" signal "L8VCC")
		(18 "In8.Cu" signal "L9GND")
		(20 "In9.Cu" signal "L10")
		(22 "In10.Cu" signal "L11GND")
		(24 "In11.Cu" signal "L12")
		(26 "In12.Cu" signal "L13GND")
		(2 "B.Cu" signal "BOTTOM")
		(9 "F.Adhes" user "F.Adhesive")
		(11 "B.Adhes" user "B.Adhesive")
		(13 "F.Paste" user "Package Geometry/Pastemask Top")
		(15 "B.Paste" user "Package Geometry/Pastemask Bottom")
		(5 "F.SilkS" user "Ref Des/Silkscreen Top")
		(7 "B.SilkS" user "Ref Des/Silkscreen Bottom")
		(1 "F.Mask" user "Board Geometry/Soldermask Top")
		(3 "B.Mask" user "Board Geometry/Soldermask Bottom")
		(17 "Dwgs.User" user "User.Drawings")
		(19 "Cmts.User" user "User.Comments")
		(21 "Eco1.User" user "User.Eco1")
		(23 "Eco2.User" user "User.Eco2")
		(25 "Edge.Cuts" user "Board Geometry/Outline")
		(27 "Margin" user)
		(31 "F.CrtYd" user "Package Geometry/Place Bound Top")
		(29 "B.CrtYd" user "Package Geometry/Place Bound Bottom")
		(35 "F.Fab" user "Ref Des/Assembly Top")
		(33 "B.Fab" user "Ref Des/Assembly Bottom")
	)
	(footprint ""
		(layer "F.Cu")
		(at 274.639024 -77.429614)
		(property "Reference" "C5D37"
			(at 0 0 0)
			(layer "F.SilkS")
			(hide yes)
			(effects
				(font
					(size 1.27 1.27)
				)
			)
		)
		(property "Value" ""
			(at 0 0 0)
			(layer "F.Fab")
			(effects
				(font
					(size 1.27 1.27)
				)
			)
		)
		(duplicate_pad_numbers_are_jumpers no)
		(fp_poly
			(pts
				(xy -0.4953 -0.2032) (xy 0.4953 -0.2032) (xy 0.4953 1.6002) (xy -0.4953 1.6002)
			)
			(stroke
				(width 0)
				(type default)
			)
			(fill no)
			(layer "F.CrtYd")
		)
		(fp_line
			(start -0.4953 -0.2032)
			(end 0.4953 -0.2032)
			(stroke
				(width 0.1)
				(type default)
			)
			(layer "F.Fab")
		)
		(fp_line
			(start -0.4953 1.6002)
			(end -0.4953 -0.2032)
			(stroke
				(width 0.1)
				(type default)
			)
			(layer "F.Fab")
		)
		(fp_line
			(start 0.4953 -0.2032)
			(end 0.4953 1.6002)
			(stroke
				(width 0.1)
				(type default)
			)
			(layer "F.Fab")
		)
		(fp_line
			(start 0.4953 1.6002)
			(end -0.4953 1.6002)
			(stroke
				(width 0.1)
				(type default)
			)
			(layer "F.Fab")
		)
		(pad "1" smd rect
			(at 0 0)
			(size 0.762 0.889)
			(layers "F.Cu" "F.Mask" "F.Paste")
			(net "PVCCMCP_CPU0")
		)
		(pad "2" smd rect
			(at 0 1.397)
			(size 0.762 0.889)
			(layers "F.Cu" "F.Mask" "F.Paste")
			(net "GND")
		)
		(zone
			(layer "F.Cu")
			(hatch none 0.5)
			(connect_pads
				(clearance 0)
			)
			(min_thickness 0.25)
			(keepout
				(tracks not_allowed)
				(vias allowed)
				(pads allowed)
				(copperpour not_allowed)
				(footprints allowed)
			)
			(placement
				(enabled no)
				(sheetname "")
			)
			(fill
				(thermal_gap 0.5)
				(thermal_bridge_width 0.5)
				(island_removal_mode 0)
			)
			(polygon
				(pts
					(xy 274.258024 -76.985114) (xy 275.020024 -76.985114) (xy 275.020024 -76.477114) (xy 274.258024 -76.477114)
				)
			)
		)
	)
	(footprint ""
		(layer "F.Cu")
		(at 386.08 -87.3125 180)
		(property "Reference" "R8E3"
			(at 0 0 180)
			(layer "F.SilkS")
			(hide yes)
			(effects
				(font
					(size 1.27 1.27)
				)
			)
		)
		(property "Value" ""
			(at 0 0 180)
			(layer "F.Fab")
			(effects
				(font
					(size 1.27 1.27)
				)
			)
		)
		(duplicate_pad_numbers_are_jumpers no)
		(fp_poly
			(pts
				(xy -0.2794 -0.1016) (xy 0.2794 -0.1016) (xy 0.2794 0.9906) (xy -0.2794 0.9906)
			)
			(stroke
				(width 0)
				(type default)
			)
			(fill no)
			(layer "F.CrtYd")
		)
		(fp_line
			(start 0.2794 0.9906)
			(end 0.2794 -0.1016)
			(stroke
				(width 0.1)
				(type default)
			)
			(layer "F.Fab")
		)
		(fp_line
			(start 0.2794 -0.1016)
			(end -0.2794 -0.1016)
			(stroke
				(width 0.1)
				(type default)
			)
			(layer "F.Fab")
		)
		(fp_line
			(start -0.2794 0.9906)
			(end 0.2794 0.9906)
			(stroke
				(width 0.1)
				(type default)
			)
			(layer "F.Fab")
		)
		(fp_line
			(start -0.2794 -0.1016)
			(end -0.2794 0.9906)
			(stroke
				(width 0.1)
				(type default)
			)
			(layer "F.Fab")
		)
		(pad "1" smd rect
			(at 0 0 180)
			(size 0.508 0.508)
			(layers "F.Cu" "F.Mask" "F.Paste")
			(net "P3V3_STBY")
		)
		(pad "2" smd rect
			(at 0 0.889 180)
			(size 0.508 0.508)
			(layers "F.Cu" "F.Mask" "F.Paste")
			(net "FM_TPM_PRES_N")
		)
		(zone
			(layer "F.Cu")
			(hatch none 0.5)
			(connect_pads
				(clearance 0)
			)
			(min_thickness 0.25)
			(keepout
				(tracks not_allowed)
				(vias allowed)
				(pads allowed)
				(copperpour not_allowed)
				(footprints allowed)
			)
			(placement
				(enabled no)
				(sheetname "")
			)
			(fill
				(thermal_gap 0.5)
				(thermal_bridge_width 0.5)
				(island_removal_mode 0)
			)
			(polygon
				(pts
					(xy 386.334 -87.9475) (xy 385.826 -87.9475) (xy 385.826 -87.5665) (xy 386.334 -87.5665)
				)
			)
		)
		(zone
			(layer "F.Cu")
			(hatch none 0.5)
			(connect_pads
				(clearance 0)
			)
			(min_thickness 0.25)
			(keepout
				(tracks allowed)
				(vias not_allowed)
				(pads allowed)
				(copperpour not_allowed)
				(footprints allowed)
			)
			(placement
				(enabled no)
				(sheetname "")
			)
			(fill
				(thermal_gap 0.5)
				(thermal_bridge_width 0.5)
				(island_removal_mode 0)
			)
			(polygon
				(pts
					(xy 386.334 -87.5665) (xy 385.826 -87.5665) (xy 385.826 -87.9475) (xy 386.334 -87.9475)
				)
			)
		)
	)
	(footprint ""
		(layer "F.Cu")
		(at 161.798 -104.14)
		(property "Reference" "C3C1"
			(at 0 0 0)
			(layer "F.SilkS")
			(hide yes)
			(effects
				(font
					(size 1.27 1.27)
				)
			)
		)
		(property "Value" ""
			(at 0 0 0)
			(layer "F.Fab")
			(effects
				(font
					(size 1.27 1.27)
				)
			)
		)
		(duplicate_pad_numbers_are_jumpers no)
		(fp_poly
			(pts
				(xy 0.3048 -0.1016) (xy 0.3048 0.9906) (xy -0.3048 0.9906) (xy -0.3048 -0.1016)
			)
			(stroke
				(width 0)
				(type default)
			)
			(fill no)
			(layer "F.CrtYd")
		)
		(fp_line
			(start -0.3048 -0.1016)
			(end -0.3048 0.9906)
			(stroke
				(width 0.1)
				(type default)
			)
			(layer "F.Fab")
		)
		(fp_line
			(start -0.3048 0.9906)
			(end 0.3048 0.9906)
			(stroke
				(width 0.1)
				(type default)
			)
			(layer "F.Fab")
		)
		(fp_line
			(start 0.3048 -0.1016)
			(end -0.3048 -0.1016)
			(stroke
				(width 0.1)
				(type default)
			)
			(layer "F.Fab")
		)
		(fp_line
			(start 0.3048 0.9906)
			(end 0.3048 -0.1016)
			(stroke
				(width 0.1)
				(type default)
			)
			(layer "F.Fab")
		)
		(pad "1" smd rect
			(at 0 0)
			(size 0.508 0.508)
			(layers "F.Cu" "F.Mask" "F.Paste")
			(net "PVCCIOMCP_CPU1")
		)
		(pad "2" smd rect
			(at 0 0.889)
			(size 0.508 0.508)
			(layers "F.Cu" "F.Mask" "F.Paste")
			(net "GND")
		)
		(zone
			(layer "F.Cu")
			(hatch none 0.5)
			(connect_pads
				(clearance 0)
			)
			(min_thickness 0.25)
			(keepout
				(tracks allowed)
				(vias not_allowed)
				(pads allowed)
				(copperpour not_allowed)
				(footprints allowed)
			)
			(placement
				(enabled no)
				(sheetname "")
			)
			(fill
				(thermal_gap 0.5)
				(thermal_bridge_width 0.5)
				(island_removal_mode 0)
			)
			(polygon
				(pts
					(xy 161.544 -103.886) (xy 162.052 -103.886) (xy 162.052 -103.505) (xy 161.544 -103.505)
				)
			)
		)
		(zone
			(layer "F.Cu")
			(hatch none 0.5)
			(connect_pads
				(clearance 0)
			)
			(min_thickness 0.25)
			(keepout
				(tracks not_allowed)
				(vias allowed)
				(pads allowed)
				(copperpour not_allowed)
				(footprints allowed)
			)
			(placement
				(enabled no)
				(sheetname "")
			)
			(fill
				(thermal_gap 0.5)
				(thermal_bridge_width 0.5)
				(island_removal_mode 0)
			)
			(polygon
				(pts
					(xy 161.544 -103.505) (xy 162.052 -103.505) (xy 162.052 -103.886) (xy 161.544 -103.886)
				)
			)
		)
	)
	(footprint ""
		(layer "F.Cu")
		(at 172.18152 -150.25624 -90)
		(property "Reference" "C4A3"
			(at 0 0 270)
			(layer "F.SilkS")
			(hide yes)
			(effects
				(font
					(size 1.27 1.27)
				)
			)
		)
		(property "Value" ""
			(at 0 0 270)
			(layer "F.Fab")
			(effects
				(font
					(size 1.27 1.27)
				)
			)
		)
		(duplicate_pad_numbers_are_jumpers no)
		(fp_rect
			(start 0.3048 0.9906)
			(end -0.3048 -0.1016)
			(stroke
				(width 0)
				(type default)
			)
			(fill no)
			(layer "F.CrtYd")
		)
		(fp_line
			(start -0.3048 0.9906)
			(end 0.3048 0.9906)
			(stroke
				(width 0.1)
				(type default)
			)
			(layer "F.Fab")
		)
		(fp_line
			(start 0.3048 0.9906)
			(end 0.3048 -0.1016)
			(stroke
				(width 0.1)
				(type default)
			)
			(layer "F.Fab")
		)
		(fp_line
			(start -0.3048 -0.1016)
			(end -0.3048 0.9906)
			(stroke
				(width 0.1)
				(type default)
			)
			(layer "F.Fab")
		)
		(fp_line
			(start 0.3048 -0.1016)
			(end -0.3048 -0.1016)
			(stroke
				(width 0.1)
				(type default)
			)
			(layer "F.Fab")
		)
		(pad "1" smd rect
			(at 0 0 270)
			(size 0.508 0.508)
			(layers "F.Cu" "F.Mask" "F.Paste")
			(net "PWRGD_PVTT_KLM_CPU1_R")
		)
		(pad "2" smd rect
			(at 0 0.889 270)
			(size 0.508 0.508)
			(layers "F.Cu" "F.Mask" "F.Paste")
			(net "GND")
		)
		(zone
			(layer "F.Cu")
			(hatch none 0.5)
			(connect_pads
				(clearance 0)
			)
			(min_thickness 0.25)
			(keepout
				(tracks not_allowed)
				(vias allowed)
				(pads allowed)
				(copperpour not_allowed)
				(footprints allowed)
			)
			(placement
				(enabled no)
				(sheetname "")
			)
			(fill
				(thermal_gap 0.5)
				(thermal_bridge_width 0.5)
				(island_removal_mode 0)
			)
			(polygon
				(pts
					(xy 171.54652 -150.00224) (xy 171.92752 -150.00224) (xy 171.92752 -150.51024) (xy 171.54652 -150.51024)
				)
			)
		)
		(zone
			(layer "F.Cu")
			(hatch none 0.5)
			(connect_pads
				(clearance 0)
			)
			(min_thickness 0.25)
			(keepout
				(tracks allowed)
				(vias not_allowed)
				(pads allowed)
				(copperpour not_allowed)
				(footprints allowed)
			)
			(placement
				(enabled no)
				(sheetname "")
			)
			(fill
				(thermal_gap 0.5)
				(thermal_bridge_width 0.5)
				(island_removal_mode 0)
			)
			(polygon
				(pts
					(xy 171.54652 -150.00224) (xy 171.92752 -150.00224) (xy 171.92752 -150.51024) (xy 171.54652 -150.51024)
				)
			)
		)
	)
	(footprint ""
		(layer "F.Cu")
		(at 401.17014 -30.67304 -90)
		(property "Reference" "R1T25"
			(at 0 0 270)
			(layer "F.SilkS")
			(hide yes)
			(effects
				(font
					(size 1.27 1.27)
				)
			)
		)
		(property "Value" ""
			(at 0 0 270)
			(layer "F.Fab")
			(effects
				(font
					(size 1.27 1.27)
				)
			)
		)
		(duplicate_pad_numbers_are_jumpers no)
		(fp_poly
			(pts
				(xy -0.2794 -0.1016) (xy 0.2794 -0.1016) (xy 0.2794 0.9906) (xy -0.2794 0.9906)
			)
			(stroke
				(width 0)
				(type default)
			)
			(fill no)
			(layer "F.CrtYd")
		)
		(fp_line
			(start -0.2794 0.9906)
			(end 0.2794 0.9906)
			(stroke
				(width 0.1)
				(type default)
			)
			(layer "F.Fab")
		)
		(fp_line
			(start 0.2794 0.9906)
			(end 0.2794 -0.1016)
			(stroke
				(width 0.1)
				(type default)
			)
			(layer "F.Fab")
		)
		(fp_line
			(start -0.2794 -0.1016)
			(end -0.2794 0.9906)
			(stroke
				(width 0.1)
				(type default)
			)
			(layer "F.Fab")
		)
		(fp_line
			(start 0.2794 -0.1016)
			(end -0.2794 -0.1016)
			(stroke
				(width 0.1)
				(type default)
			)
			(layer "F.Fab")
		)
		(pad "1" smd rect
			(at 0 0 270)
			(size 0.508 0.508)
			(layers "F.Cu" "F.Mask" "F.Paste")
			(net "A_USB2BVRES")
		)
		(pad "2" smd rect
			(at 0 0.889 270)
			(size 0.508 0.508)
			(layers "F.Cu" "F.Mask" "F.Paste")
			(net "GND")
		)
		(zone
			(layer "F.Cu")
			(hatch none 0.5)
			(connect_pads
				(clearance 0)
			)
			(min_thickness 0.25)
			(keepout
				(tracks not_allowed)
				(vias allowed)
				(pads allowed)
				(copperpour not_allowed)
				(footprints allowed)
			)
			(placement
				(enabled no)
				(sheetname "")
			)
			(fill
				(thermal_gap 0.5)
				(thermal_bridge_width 0.5)
				(island_removal_mode 0)
			)
			(polygon
				(pts
					(xy 400.53514 -30.92704) (xy 400.53514 -30.41904) (xy 400.91614 -30.41904) (xy 400.91614 -30.92704)
				)
			)
		)
		(zone
			(layer "F.Cu")
			(hatch none 0.5)
			(connect_pads
				(clearance 0)
			)
			(min_thickness 0.25)
			(keepout
				(tracks allowed)
				(vias not_allowed)
				(pads allowed)
				(copperpour not_allowed)
				(footprints allowed)
			)
			(placement
				(enabled no)
				(sheetname "")
			)
			(fill
				(thermal_gap 0.5)
				(thermal_bridge_width 0.5)
				(island_removal_mode 0)
			)
			(polygon
				(pts
					(xy 400.91614 -30.92704) (xy 400.91614 -30.41904) (xy 400.53514 -30.41904) (xy 400.53514 -30.92704)
				)
			)
		)
	)
	(footprint ""
		(layer "F.Cu")
		(at 401.2438 -130.1496 180)
		(property "Reference" "C8B3"
			(at 0 0 180)
			(layer "F.SilkS")
			(hide yes)
			(effects
				(font
					(size 1.27 1.27)
				)
			)
		)
		(property "Value" ""
			(at 0 0 180)
			(layer "F.Fab")
			(effects
				(font
					(size 1.27 1.27)
				)
			)
		)
		(duplicate_pad_numbers_are_jumpers no)
		(fp_poly
			(pts
				(xy -0.4953 -0.2032) (xy 0.4953 -0.2032) (xy 0.4953 1.6002) (xy -0.4953 1.6002)
			)
			(stroke
				(width 0)
				(type default)
			)
			(fill no)
			(layer "F.CrtYd")
		)
		(fp_line
			(start 0.4953 1.6002)
			(end -0.4953 1.6002)
			(stroke
				(width 0.1)
				(type default)
			)
			(layer "F.Fab")
		)
		(fp_line
			(start 0.4953 -0.2032)
			(end 0.4953 1.6002)
			(stroke
				(width 0.1)
				(type default)
			)
			(layer "F.Fab")
		)
		(fp_line
			(start -0.4953 1.6002)
			(end -0.4953 -0.2032)
			(stroke
				(width 0.1)
				(type default)
			)
			(layer "F.Fab")
		)
		(fp_line
			(start -0.4953 -0.2032)
			(end 0.4953 -0.2032)
			(stroke
				(width 0.1)
				(type default)
			)
			(layer "F.Fab")
		)
		(pad "1" smd rect
			(at 0 0 180)
			(size 0.762 0.889)
			(layers "F.Cu" "F.Mask" "F.Paste")
			(net "P1V8_PCH_STBY")
		)
		(pad "2" smd rect
			(at 0 1.397 180)
			(size 0.762 0.889)
			(layers "F.Cu" "F.Mask" "F.Paste")
			(net "GND")
		)
		(zone
			(layer "F.Cu")
			(hatch none 0.5)
			(connect_pads
				(clearance 0)
			)
			(min_thickness 0.25)
			(keepout
				(tracks not_allowed)
				(vias allowed)
				(pads allowed)
				(copperpour not_allowed)
				(footprints allowed)
			)
			(placement
				(enabled no)
				(sheetname "")
			)
			(fill
				(thermal_gap 0.5)
				(thermal_bridge_width 0.5)
				(island_removal_mode 0)
			)
			(polygon
				(pts
					(xy 401.6248 -130.5941) (xy 400.8628 -130.5941) (xy 400.8628 -131.1021) (xy 401.6248 -131.1021)
				)
			)
		)
	)
	(footprint ""
		(layer "F.Cu")
		(at 245.7323 -149.8092 -90)
		(property "Reference" "C5A1"
			(at 1.848866 0.752348 270)
			(unlocked yes)
			(layer "F.SilkS")
			(effects
				(font
					(size 1.27 0.9652)
					(thickness 0.1524)
				)
			)
		)
		(property "Value" ""
			(at 0 0 270)
			(layer "F.Fab")
			(effects
				(font
					(size 1.27 1.27)
				)
			)
		)
		(duplicate_pad_numbers_are_jumpers no)
		(fp_rect
			(start -0.500126 1.598422)
			(end 0.500126 -0.201422)
			(stroke
				(width 0)
				(type default)
			)
			(fill no)
			(layer "F.CrtYd")
		)
		(fp_line
			(start -0.500126 1.598422)
			(end -0.500126 -0.201422)
			(stroke
				(width 0.1)
				(type default)
			)
			(layer "F.Fab")
		)
		(fp_line
			(start 0.500126 1.598422)
			(end -0.500126 1.598422)
			(stroke
				(width 0.1)
				(type default)
			)
			(layer "F.Fab")
		)
		(fp_line
			(start -0.500126 -0.201422)
			(end 0.500126 -0.201422)
			(stroke
				(width 0.1)
				(type default)
			)
			(layer "F.Fab")
		)
		(fp_line
			(start 0.500126 -0.201422)
			(end 0.500126 1.598422)
			(stroke
				(width 0.1)
				(type default)
			)
			(layer "F.Fab")
		)
		(pad "1" smd rect
			(at 0 0 180)
			(size 0.889 0.9906)
			(layers "F.Cu" "F.Mask" "F.Paste")
			(net "PVDDQ_DEF")
		)
		(pad "2" smd rect
			(at 0 1.397 180)
			(size 0.889 0.9906)
			(layers "F.Cu" "F.Mask" "F.Paste")
			(net "GND")
		)
		(zone
			(layer "F.Cu")
			(hatch none 0.5)
			(connect_pads
				(clearance 0)
			)
			(min_thickness 0.25)
			(keepout
				(tracks allowed)
				(vias not_allowed)
				(pads allowed)
				(copperpour not_allowed)
				(footprints allowed)
			)
			(placement
				(enabled no)
				(sheetname "")
			)
			(fill
				(thermal_gap 0.5)
				(thermal_bridge_width 0.5)
				(island_removal_mode 0)
			)
			(polygon
				(pts
					(xy 244.7798 -150.3045) (xy 244.7798 -149.3139) (xy 245.2878 -149.3139) (xy 245.2878 -150.3045)
				)
			)
		)
		(zone
			(layer "F.Cu")
			(hatch none 0.5)
			(connect_pads
				(clearance 0)
			)
			(min_thickness 0.25)
			(keepout
				(tracks not_allowed)
				(vias allowed)
				(pads allowed)
				(copperpour not_allowed)
				(footprints allowed)
			)
			(placement
				(enabled no)
				(sheetname "")
			)
			(fill
				(thermal_gap 0.5)
				(thermal_bridge_width 0.5)
				(island_removal_mode 0)
			)
			(polygon
				(pts
					(xy 244.7798 -150.3045) (xy 244.7798 -149.3139) (xy 245.2878 -149.3139) (xy 245.2878 -150.3045)
				)
			)
		)
	)
	(footprint ""
		(layer "F.Cu")
		(at 352.9838 -99.50323 90)
		(property "Reference" "R7C25"
			(at 0 0 90)
			(layer "F.SilkS")
			(hide yes)
			(effects
				(font
					(size 1.27 1.27)
				)
			)
		)
		(property "Value" ""
			(at 0 0 90)
			(layer "F.Fab")
			(effects
				(font
					(size 1.27 1.27)
				)
			)
		)
		(duplicate_pad_numbers_are_jumpers no)
		(fp_poly
			(pts
				(xy -0.2794 -0.1016) (xy 0.2794 -0.1016) (xy 0.2794 0.9906) (xy -0.2794 0.9906)
			)
			(stroke
				(width 0)
				(type default)
			)
			(fill no)
			(layer "F.CrtYd")
		)
		(fp_line
			(start 0.2794 -0.1016)
			(end -0.2794 -0.1016)
			(stroke
				(width 0.1)
				(type default)
			)
			(layer "F.Fab")
		)
		(fp_line
			(start -0.2794 -0.1016)
			(end -0.2794 0.9906)
			(stroke
				(width 0.1)
				(type default)
			)
			(layer "F.Fab")
		)
		(fp_line
			(start 0.2794 0.9906)
			(end 0.2794 -0.1016)
			(stroke
				(width 0.1)
				(type default)
			)
			(layer "F.Fab")
		)
		(fp_line
			(start -0.2794 0.9906)
			(end 0.2794 0.9906)
			(stroke
				(width 0.1)
				(type default)
			)
			(layer "F.Fab")
		)
		(pad "1" smd rect
			(at 0 0 90)
			(size 0.508 0.508)
			(layers "F.Cu" "F.Mask" "F.Paste")
			(net "VR_PVCCIO_CPU0_OCSET")
		)
		(pad "2" smd rect
			(at 0 0.889 90)
			(size 0.508 0.508)
			(layers "F.Cu" "F.Mask" "F.Paste")
			(net "GND")
		)
		(zone
			(layer "F.Cu")
			(hatch none 0.5)
			(connect_pads
				(clearance 0)
			)
			(min_thickness 0.25)
			(keepout
				(tracks allowed)
				(vias not_allowed)
				(pads allowed)
				(copperpour not_allowed)
				(footprints allowed)
			)
			(placement
				(enabled no)
				(sheetname "")
			)
			(fill
				(thermal_gap 0.5)
				(thermal_bridge_width 0.5)
				(island_removal_mode 0)
			)
			(polygon
				(pts
					(xy 353.2378 -99.24923) (xy 353.2378 -99.75723) (xy 353.6188 -99.75723) (xy 353.6188 -99.24923)
				)
			)
		)
		(zone
			(layer "F.Cu")
			(hatch none 0.5)
			(connect_pads
				(clearance 0)
			)
			(min_thickness 0.25)
			(keepout
				(tracks not_allowed)
				(vias allowed)
				(pads allowed)
				(copperpour not_allowed)
				(footprints allowed)
			)
			(placement
				(enabled no)
				(sheetname "")
			)
			(fill
				(thermal_gap 0.5)
				(thermal_bridge_width 0.5)
				(island_removal_mode 0)
			)
			(polygon
				(pts
					(xy 353.6188 -99.24923) (xy 353.6188 -99.75723) (xy 353.2378 -99.75723) (xy 353.2378 -99.24923)
				)
			)
		)
	)
)
